(kicad_pcb
	(version 20221018)
	(generator pcbnew)
	(general
    (thickness 1.7403)
  )
	(paper "A4")
	(title_block
    (title "Data Center RDIMM DDR4 Tester")
    (date "2024-09-30")
    (rev "1.2.4")
		(comment 9 "footprints 311-320 of 690")
	)
	(layers
    (0 "F.Cu" signal)
    (1 "In1.Cu" power)
    (2 "In2.Cu" signal)
    (3 "In3.Cu" power)
    (4 "In4.Cu" power)
    (5 "In5.Cu" signal)
    (6 "In6.Cu" power)
    (7 "In7.Cu" signal)
    (8 "In8.Cu" power)
    (9 "In9.Cu" signal)
    (10 "In10.Cu" power)
    (31 "B.Cu" signal)
    (32 "B.Adhes" user "B.Adhesive")
    (33 "F.Adhes" user "F.Adhesive")
    (34 "B.Paste" user)
    (35 "F.Paste" user)
    (36 "B.SilkS" user "B.Silkscreen")
    (37 "F.SilkS" user "F.Silkscreen")
    (38 "B.Mask" user)
    (39 "F.Mask" user)
    (40 "Dwgs.User" user "User.Drawings")
    (41 "Cmts.User" user "User.Comments")
    (42 "Eco1.User" user "User.Eco1")
    (43 "Eco2.User" user "User.Eco2")
    (44 "Edge.Cuts" user)
    (45 "Margin" user)
    (46 "B.CrtYd" user "B.Courtyard")
    (47 "F.CrtYd" user "F.Courtyard")
    (48 "B.Fab" user)
    (49 "F.Fab" user)
  )
	(footprint "data-center-rdimm-ddr4-tester-footprints:C_0402_1005Metric" (layer "F.Cu")
    (at 254.71 82.715 180)
    (descr "Capacitor SMD 0402")
    (tags "capacitor SMD 0402")
    (property "Author" "Antmicro")
    (property "Dielectric" "X5R")
    (property "License" "Apache-2.0")
    (property "MPN" "GRM155R61H104KE14D")
    (property "Manufacturer" "Murata")
    (property "Sheetfile" "fmc_hpc.kicad_sch")
    (property "Sheetname" "FMC HPC")
    (property "Val" "100n")
    (property "Voltage" "50V")
    (property "ki_description" " ")
    (attr smd)
    (fp_text reference "C267" (at -0.78 -0.295 180) (layer "F.SilkS")
        (effects (font (size 0.7 0.7) (thickness 0.15)) (justify left bottom))
    )
    (fp_text value "C_100n_0402" (at 0 1.4 180) (layer "F.Fab") hide
        (effects (font (size 0.7 0.7) (thickness 0.15)) (justify left bottom))
    )
    (fp_text user "${REFERENCE}" (at -0.932 3.168 180) (layer "F.Fab") hide
        (effects (font (size 0.7 0.7) (thickness 0.15)) (justify left bottom))
    )
    (fp_text user "License: Apache-2.0" (at -0.932 5.17 180) (layer "F.Fab") hide
        (effects (font (size 0.7 0.7) (thickness 0.15)) (justify left bottom))
    )
    (fp_text user "Author: Antmicro" (at -0.932 4.17 180) (layer "F.Fab") hide
        (effects (font (size 0.7 0.7) (thickness 0.15)) (justify left bottom))
    )
    (fp_rect (start -0.94 -0.47) (end 0.94 0.47)
      (stroke (width 0.05) (type solid)) (fill none) (layer "F.CrtYd"))
    (fp_rect (start -0.499 -0.249) (end 0.499 0.249)
      (stroke (width 0.15) (type solid)) (fill none) (layer "F.Fab"))
    (pad "1" smd roundrect (at -0.484 0 180) (size 0.59 0.64) (layers "F.Cu" "F.Paste" "F.Mask") (roundrect_rratio 0.25)
      (net 464 "/FMC HPC/GTX_TX4_C_P") (pintype "passive"))
    (pad "2" smd roundrect (at 0.484 0 180) (size 0.59 0.64) (layers "F.Cu" "F.Paste" "F.Mask") (roundrect_rratio 0.25)
      (net 465 "GTX_TX4_P") (pintype "passive"))
  )
	(footprint "data-center-rdimm-ddr4-tester-footprints:R_0201" (layer "F.Cu")
    (at 160.325 104.3 90)
    (descr "Resistor SMD 0201")
    (tags "resistor SMD 0201")
    (property "Author" "Antmicro")
    (property "License" "Apache-2.0")
    (property "MPN" "CR0201-FX-0R00GLF")
    (property "Manufacturer" "Bourns")
    (property "Sheetfile" "ethernet.kicad_sch")
    (property "Sheetname" "Ethernet")
    (property "Tolerance" "1%")
    (property "Val" "0R")
    (property "ki_description" "0R resistor in 0201 package with 1% tolerance")
    (attr smd)
    (fp_text reference "R102" (at 0.62 0.325 90) (layer "F.SilkS")
        (effects (font (size 0.7 0.7) (thickness 0.15)) (justify left bottom))
    )
    (fp_text value "R_0R_0201" (at 0 1.25 90) (layer "F.Fab") hide
        (effects (font (size 0.7 0.7) (thickness 0.15)) (justify left bottom))
    )
    (fp_text user "Author: Antmicro" (at -0.71 5.25 90) (layer "F.Fab") hide
        (effects (font (size 0.7 0.7) (thickness 0.15)) (justify left bottom))
    )
    (fp_text user "${REFERENCE}" (at -0.71 3.25 90) (layer "F.Fab") hide
        (effects (font (size 0.7 0.7) (thickness 0.15)) (justify left bottom))
    )
    (fp_text user "License: Apache-2.0" (at -0.71 4.25 90) (layer "F.Fab") hide
        (effects (font (size 0.7 0.7) (thickness 0.15)) (justify left bottom))
    )
    (fp_rect (start -0.71 -0.36) (end 0.71 0.36)
      (stroke (width 0.05) (type solid)) (fill none) (layer "F.CrtYd"))
    (fp_rect (start -0.3 -0.15) (end 0.298 0.148)
      (stroke (width 0.15) (type solid)) (fill none) (layer "F.Fab"))
    (pad "" smd roundrect (at -0.346 0 90) (size 0.318 0.36) (layers "F.Paste") (roundrect_rratio 0.25))
    (pad "" smd roundrect (at 0.344 0 90) (size 0.318 0.36) (layers "F.Paste") (roundrect_rratio 0.25))
    (pad "1" smd roundrect (at -0.32 0 90) (size 0.46 0.4) (layers "F.Cu" "F.Mask") (roundrect_rratio 0.25)
      (net 829 "/Ethernet/ETH3_BP_N") (pintype "passive"))
    (pad "2" smd roundrect (at 0.32 0 90) (size 0.46 0.4) (layers "F.Cu" "F.Mask") (roundrect_rratio 0.25)
      (net 174 "/Ethernet/ETH3_N") (pintype "passive"))
  )
	(footprint "data-center-rdimm-ddr4-tester-footprints:NetTie-2_SMD_Pad0.127mm" (layer "F.Cu")
    (at 113.12 108.95)
    (descr "Net tie, 2 pin, 0.127mm  SMD pads")
    (tags "net tie")
    (property "Author" "Antmicro")
    (property "License" "Apache-2.0")
    (property "MPN" "")
    (property "Manufacturer" "")
    (property "Sheetfile" "supply.kicad_sch")
    (property "Sheetname" "Supply")
    (property "ki_description" "Net tie, 2 pins")
    (property "ki_keywords" "net tie short")
    (attr through_hole exclude_from_pos_files)
    (net_tie_pad_groups "1, 2")
    (fp_text reference "NT8" (at -0.128 -1.345) (layer "F.SilkS") hide
        (effects (font (size 0.7 0.7) (thickness 0.15)) (justify left bottom))
    )
    (fp_text value "Net-Tie_2" (at 0 1.199) (layer "F.Fab") hide
        (effects (font (size 0.7 0.7) (thickness 0.15)) (justify left bottom))
    )
    (fp_text user "Author: Antmicro" (at -0.128 4.4) (layer "F.Fab") hide
        (effects (font (size 0.7 0.7) (thickness 0.15)) (justify left bottom))
    )
    (fp_text user "${REFERENCE}" (at -0.128 3.2) (layer "F.Fab") hide
        (effects (font (size 0.7 0.7) (thickness 0.15)) (justify left bottom))
    )
    (fp_text user "License: Apache-2.0" (at -0.128 5.6) (layer "F.Fab") hide
        (effects (font (size 0.7 0.7) (thickness 0.15)) (justify left bottom))
    )
    (fp_poly
      (pts
        (xy -0.0635 -0.0635)
        (xy 0.0625 -0.0635)
        (xy 0.0625 0.0635)
        (xy -0.0635 0.0635)
      )

      (stroke (width 0) (type solid)) (fill solid) (layer "F.Cu"))
    (pad "1" smd roundrect (at -0.127 0 180) (size 0.127 0.127) (layers "F.Cu") (roundrect_rratio 0.5)
      (chamfer_ratio 0) (chamfer top_left bottom_left)
      (net 839 "/Supply/3V3_SEN_+") (pinfunction "1") (pintype "passive"))
    (pad "2" smd roundrect (at 0.126 0) (size 0.127 0.127) (layers "F.Cu") (roundrect_rratio 0.5)
      (chamfer_ratio 0) (chamfer top_left bottom_left)
      (net 304 "VCC3V3") (pinfunction "2") (pintype "passive"))
  )
	(footprint "data-center-rdimm-ddr4-tester-footprints:C_0402_1005Metric" (layer "F.Cu")
    (at 254.71 77.635 180)
    (descr "Capacitor SMD 0402")
    (tags "capacitor SMD 0402")
    (property "Author" "Antmicro")
    (property "Dielectric" "X5R")
    (property "License" "Apache-2.0")
    (property "MPN" "GRM155R61H104KE14D")
    (property "Manufacturer" "Murata")
    (property "Sheetfile" "fmc_hpc.kicad_sch")
    (property "Sheetname" "FMC HPC")
    (property "Val" "100n")
    (property "Voltage" "50V")
    (property "ki_description" " ")
    (attr smd)
    (fp_text reference "C269" (at -0.78 -0.375 180) (layer "F.SilkS")
        (effects (font (size 0.7 0.7) (thickness 0.15)) (justify left bottom))
    )
    (fp_text value "C_100n_0402" (at 0 1.4 180) (layer "F.Fab") hide
        (effects (font (size 0.7 0.7) (thickness 0.15)) (justify left bottom))
    )
    (fp_text user "Author: Antmicro" (at -0.932 4.17 180) (layer "F.Fab") hide
        (effects (font (size 0.7 0.7) (thickness 0.15)) (justify left bottom))
    )
    (fp_text user "License: Apache-2.0" (at -0.932 5.17 180) (layer "F.Fab") hide
        (effects (font (size 0.7 0.7) (thickness 0.15)) (justify left bottom))
    )
    (fp_text user "${REFERENCE}" (at -0.932 3.168 180) (layer "F.Fab") hide
        (effects (font (size 0.7 0.7) (thickness 0.15)) (justify left bottom))
    )
    (fp_rect (start -0.94 -0.47) (end 0.94 0.47)
      (stroke (width 0.05) (type solid)) (fill none) (layer "F.CrtYd"))
    (fp_rect (start -0.499 -0.249) (end 0.499 0.249)
      (stroke (width 0.15) (type solid)) (fill none) (layer "F.Fab"))
    (pad "1" smd roundrect (at -0.484 0 180) (size 0.59 0.64) (layers "F.Cu" "F.Paste" "F.Mask") (roundrect_rratio 0.25)
      (net 480 "/FMC HPC/GTX_TX5_C_P") (pintype "passive"))
    (pad "2" smd roundrect (at 0.484 0 180) (size 0.59 0.64) (layers "F.Cu" "F.Paste" "F.Mask") (roundrect_rratio 0.25)
      (net 481 "GTX_TX5_P") (pintype "passive"))
  )
	(footprint "data-center-rdimm-ddr4-tester-footprints:R_0402_1005Metric" (layer "F.Cu")
    (at 256.2 89.3)
    (descr "Resistor SMD 0402")
    (tags "resistor SMD 0402")
    (property "Author" "Antmicro")
    (property "License" "Apache-2.0")
    (property "MPN" "CR0402-FX-4701GLF")
    (property "Manufacturer" "Bourns")
    (property "Sheetfile" "fmc_hpc.kicad_sch")
    (property "Sheetname" "FMC HPC")
    (property "Tolerance" "1%")
    (property "Val" "4k7")
    (property "ki_description" "4k7 resistor in 0402 package with 1% tolerance")
    (attr smd)
    (fp_text reference "R160" (at 0.66 0.35) (layer "F.SilkS")
        (effects (font (size 0.7 0.7) (thickness 0.15)) (justify left bottom))
    )
    (fp_text value "R_4k7_0402" (at 0 1.4) (layer "F.Fab") hide
        (effects (font (size 0.7 0.7) (thickness 0.15)) (justify left bottom))
    )
    (fp_text user "License: Apache-2.0" (at -0.95 5.169) (layer "F.Fab") hide
        (effects (font (size 0.7 0.7) (thickness 0.15)) (justify left bottom))
    )
    (fp_text user "${REFERENCE}" (at -0.95 3.168) (layer "F.Fab") hide
        (effects (font (size 0.7 0.7) (thickness 0.15)) (justify left bottom))
    )
    (fp_text user "Author: Antmicro" (at -0.95 4.169) (layer "F.Fab") hide
        (effects (font (size 0.7 0.7) (thickness 0.15)) (justify left bottom))
    )
    (fp_rect (start -0.93 -0.47) (end 0.93 0.47)
      (stroke (width 0.05) (type solid)) (fill none) (layer "F.CrtYd"))
    (fp_rect (start -0.5 -0.25) (end 0.5 0.25)
      (stroke (width 0.15) (type solid)) (fill none) (layer "F.Fab"))
    (pad "1" smd roundrect (at -0.485 0) (size 0.59 0.64) (layers "F.Cu" "F.Paste" "F.Mask") (roundrect_rratio 0.25)
      (net 143 "3V3_SYS") (pintype "passive"))
    (pad "2" smd roundrect (at 0.485 0) (size 0.59 0.64) (layers "F.Cu" "F.Paste" "F.Mask") (roundrect_rratio 0.25)
      (net 908 "FMC_SDA_3V3") (pintype "passive"))
  )
	(footprint "data-center-rdimm-ddr4-tester-footprints:Fiducial_1mm_Mask2mm" (layer "F.Cu")
    (at 257 128)
    (descr "Circular Fiducial, 1mm bare copper, 3mm soldermask opening")
    (tags "fiducial")
    (property "Author" "Antmicro")
    (property "License" "Apache-2.0")
    (property "MPN" "")
    (property "Manufacturer" "")
    (property "Sheetfile" "data-center-rdimm-ddr4-tester.kicad_sch")
    (property "Sheetname" "")
    (property "exclude_from_bom" "")
    (property "ki_description" "Fiducial Marker for use with single board only")
    (attr exclude_from_pos_files exclude_from_bom)
    (fp_text reference "FID3" (at -1.13 -1.14) (layer "F.SilkS")
        (effects (font (size 0.7 0.7) (thickness 0.15)) (justify left bottom))
    )
    (fp_text value "Fiducial_1mm_Mask2mm" (at 0 2.2) (layer "F.Fab")
        (effects (font (size 0.7 0.7) (thickness 0.15)) (justify left bottom))
    )
    (fp_text user "Author: Antmicro" (at -1.25 5.803) (layer "F.Fab") hide
        (effects (font (size 0.7 0.7) (thickness 0.15)) (justify left bottom))
    )
    (fp_text user "${REFERENCE}" (at -1.25 4.603) (layer "F.Fab") hide
        (effects (font (size 0.7 0.7) (thickness 0.15)) (justify left bottom))
    )
    (fp_text user "License: Apache-2.0" (at -1.25 7.003) (layer "F.Fab") hide
        (effects (font (size 0.7 0.7) (thickness 0.15)) (justify left bottom))
    )
    (fp_circle (center 0 0) (end 1.24 0)
      (stroke (width 0.05) (type solid)) (fill none) (layer "F.CrtYd"))
    (fp_circle (center 0 0) (end 0.999 0)
      (stroke (width 0.15) (type solid)) (fill none) (layer "F.Fab"))
    (pad "" smd circle (at 0 0) (size 1 1) (layers "F.Cu" "F.Mask")
      (solder_mask_margin 0.5) (clearance 0.5))
  )
	(footprint "data-center-rdimm-ddr4-tester-footprints:Testpoint_smd_1mm" (layer "F.Cu")
    (at 228.899999 125.3 180)
    (property "Author" "Antmicro")
    (property "License" "Apache-2.0")
    (property "MPN" "")
    (property "Manufacturer" "")
    (property "Sheetfile" "supply.kicad_sch")
    (property "Sheetname" "Supply")
    (property "ki_description" "Test Point 1mm")
    (attr exclude_from_pos_files)
    (fp_text reference "TP13" (at 1.589999 -1.44 180) (layer "F.SilkS")
        (effects (font (size 0.7 0.7) (thickness 0.15)) (justify left bottom))
    )
    (fp_text value "TP_1mm_SMD" (at 0 1.4 180) (layer "F.Fab") hide
        (effects (font (size 0.7 0.7) (thickness 0.15)) (justify left bottom))
    )
    (fp_text user "License: Apache-2.0" (at -0.5 5.2 180) (layer "F.Fab") hide
        (effects (font (size 0.7 0.7) (thickness 0.15)) (justify left bottom))
    )
    (fp_text user "${REFERENCE}" (at -0.5 2.8 180) (layer "F.Fab") hide
        (effects (font (size 0.7 0.7) (thickness 0.15)) (justify left bottom))
    )
    (fp_text user "Author: Antmicro" (at -0.5 4 180) (layer "F.Fab") hide
        (effects (font (size 0.7 0.7) (thickness 0.15)) (justify left bottom))
    )
    (pad "1" smd circle (at 0 0 180) (size 1 1) (layers "F.Cu" "F.Mask")
      (net 860 "/Supply/~{CLR}") (pinfunction "1") (pintype "passive"))
  )
	(footprint "data-center-rdimm-ddr4-tester-footprints:NetTie-2_SMD_Pad0.127mm" (layer "F.Cu")
    (at 119.675 84.367 -90)
    (descr "Net tie, 2 pin, 0.127mm  SMD pads")
    (tags "net tie")
    (property "Author" "Antmicro")
    (property "License" "Apache-2.0")
    (property "MPN" "")
    (property "Manufacturer" "")
    (property "Sheetfile" "supply.kicad_sch")
    (property "Sheetname" "Supply")
    (property "ki_description" "Net tie, 2 pins")
    (property "ki_keywords" "net tie short")
    (attr through_hole exclude_from_pos_files)
    (net_tie_pad_groups "1, 2")
    (fp_text reference "NT2" (at -0.128 -1.345 -90) (layer "F.SilkS") hide
        (effects (font (size 0.7 0.7) (thickness 0.15)) (justify left bottom))
    )
    (fp_text value "Net-Tie_2" (at 0 1.199 -90) (layer "F.Fab") hide
        (effects (font (size 0.7 0.7) (thickness 0.15)) (justify left bottom))
    )
    (fp_text user "${REFERENCE}" (at -0.128 3.2 -90) (layer "F.Fab") hide
        (effects (font (size 0.7 0.7) (thickness 0.15)) (justify left bottom))
    )
    (fp_text user "Author: Antmicro" (at -0.128 4.4 -90) (layer "F.Fab") hide
        (effects (font (size 0.7 0.7) (thickness 0.15)) (justify left bottom))
    )
    (fp_text user "License: Apache-2.0" (at -0.128 5.6 -90) (layer "F.Fab") hide
        (effects (font (size 0.7 0.7) (thickness 0.15)) (justify left bottom))
    )
    (fp_poly
      (pts
        (xy -0.0635 -0.0635)
        (xy 0.0625 -0.0635)
        (xy 0.0625 0.0635)
        (xy -0.0635 0.0635)
      )

      (stroke (width 0) (type solid)) (fill solid) (layer "F.Cu"))
    (pad "1" smd roundrect (at -0.127 0 90) (size 0.127 0.127) (layers "F.Cu") (roundrect_rratio 0.5)
      (chamfer_ratio 0) (chamfer top_left bottom_left)
      (net 833 "/Supply/VDDQ_SEN_+") (pinfunction "1") (pintype "passive"))
    (pad "2" smd roundrect (at 0.126 0 270) (size 0.127 0.127) (layers "F.Cu") (roundrect_rratio 0.5)
      (chamfer_ratio 0) (chamfer top_left bottom_left)
      (net 301 "VDD1V2") (pinfunction "2") (pintype "passive"))
  )
	(footprint "data-center-rdimm-ddr4-tester-footprints:R_0402_1005Metric" (layer "F.Cu")
    (at 244.772901 120.82 180)
    (descr "Resistor SMD 0402")
    (tags "resistor SMD 0402")
    (property "Author" "Antmicro")
    (property "License" "Apache-2.0")
    (property "MPN" "CR0402-FX-33R0GLF")
    (property "Manufacturer" "Bourns")
    (property "Sheetfile" "fmc_hpc.kicad_sch")
    (property "Sheetname" "FMC HPC")
    (property "Tolerance" "1%")
    (property "Val" "33R")
    (property "ki_description" "33R resistor in 0402 package with 1% tolerance")
    (attr smd)
    (fp_text reference "R150" (at 0.582901 1.57 180) (layer "F.SilkS")
        (effects (font (size 0.7 0.7) (thickness 0.15)) (justify left bottom))
    )
    (fp_text value "R_33R_0402" (at 0 1.4 180) (layer "F.Fab") hide
        (effects (font (size 0.7 0.7) (thickness 0.15)) (justify left bottom))
    )
    (fp_text user "${REFERENCE}" (at -0.95 3.168 180) (layer "F.Fab") hide
        (effects (font (size 0.7 0.7) (thickness 0.15)) (justify left bottom))
    )
    (fp_text user "Author: Antmicro" (at -0.95 4.169 180) (layer "F.Fab") hide
        (effects (font (size 0.7 0.7) (thickness 0.15)) (justify left bottom))
    )
    (fp_text user "License: Apache-2.0" (at -0.95 5.169 180) (layer "F.Fab") hide
        (effects (font (size 0.7 0.7) (thickness 0.15)) (justify left bottom))
    )
    (fp_rect (start -0.93 -0.47) (end 0.93 0.47)
      (stroke (width 0.05) (type solid)) (fill none) (layer "F.CrtYd"))
    (fp_rect (start -0.5 -0.25) (end 0.5 0.25)
      (stroke (width 0.15) (type solid)) (fill none) (layer "F.Fab"))
    (pad "1" smd roundrect (at -0.485 0 180) (size 0.59 0.64) (layers "F.Cu" "F.Paste" "F.Mask") (roundrect_rratio 0.25)
      (net 903 "/FMC HPC/GTR_REFCLK2_R_P") (pintype "passive"))
    (pad "2" smd roundrect (at 0.485 0 180) (size 0.59 0.64) (layers "F.Cu" "F.Paste" "F.Mask") (roundrect_rratio 0.25)
      (net 893 "GTR_REFCLK2_C_P") (pintype "passive"))
  )
	(footprint "data-center-rdimm-ddr4-tester-footprints:C_0402_1005Metric" (layer "F.Cu")
    (at 248.555 119.81 180)
    (descr "Capacitor SMD 0402")
    (tags "capacitor SMD 0402")
    (property "Author" "Antmicro")
    (property "Dielectric" "X5R")
    (property "License" "Apache-2.0")
    (property "MPN" "GRM155R61H104KE14D")
    (property "Manufacturer" "Murata")
    (property "Sheetfile" "pcie.kicad_sch")
    (property "Sheetname" "FPGA banks 115-116")
    (property "Val" "100n")
    (property "Voltage" "50V")
    (property "ki_description" " ")
    (attr smd)
    (fp_text reference "C247" (at 1.485 1.56 180) (layer "F.SilkS")
        (effects (font (size 0.7 0.7) (thickness 0.15)) (justify left bottom))
    )
    (fp_text value "C_100n_0402" (at 0 1.4 180) (layer "F.Fab") hide
        (effects (font (size 0.7 0.7) (thickness 0.15)) (justify left bottom))
    )
    (fp_text user "${REFERENCE}" (at -0.932 3.168 180) (layer "F.Fab") hide
        (effects (font (size 0.7 0.7) (thickness 0.15)) (justify left bottom))
    )
    (fp_text user "Author: Antmicro" (at -0.932 4.17 180) (layer "F.Fab") hide
        (effects (font (size 0.7 0.7) (thickness 0.15)) (justify left bottom))
    )
    (fp_text user "License: Apache-2.0" (at -0.932 5.17 180) (layer "F.Fab") hide
        (effects (font (size 0.7 0.7) (thickness 0.15)) (justify left bottom))
    )
    (fp_rect (start -0.94 -0.47) (end 0.94 0.47)
      (stroke (width 0.05) (type solid)) (fill none) (layer "F.CrtYd"))
    (fp_rect (start -0.499 -0.249) (end 0.499 0.249)
      (stroke (width 0.15) (type solid)) (fill none) (layer "F.Fab"))
    (pad "1" smd roundrect (at -0.484 0 180) (size 0.59 0.64) (layers "F.Cu" "F.Paste" "F.Mask") (roundrect_rratio 0.25)
      (net 408 "GTR_REFCLK0_C_N") (pintype "passive"))
    (pad "2" smd roundrect (at 0.484 0 180) (size 0.59 0.64) (layers "F.Cu" "F.Paste" "F.Mask") (roundrect_rratio 0.25)
      (net 409 "/FPGA banks 115-116/GTR_REFCLK0_N") (pintype "passive"))
  )
)
